# T6G (Grand Teton) — schematic netlist excerpt (pin names and nets, part order shuffled) for the footprints in the layout excerpt that follows; sources: Cadence DE-HDL packaged netlist, KiCad conversion of 04192023_DAF0TMB3IC0_F0TG_MB_C_brd_V02_OCP.brd

C6010  Q_CAP  10UF 16V 10% X6S  pkg C0805  page 112 : A = P3V3_AUX ; B = GND
C1050  Q_CAP  1UF 4V 20% X6S  pkg 0201  page 312 : A = P0V9_CPU0_RT3_2A ; B = GND
PR127  Q_RES  0 5% EMPTY  pkg 0402LF  page 207 : A = PVDD11_S3_P0_RESET_N_R ; B = GND

(kicad_pcb
	(version 20260206)
	(generator "pcbnew")
	(generator_version "10.0")
	(general
		(thickness 1.6)
		(legacy_teardrops no)
	)
	(paper "A4")
	(title_block
		(title "04192023_DAF0TMB3IC0_F0TG_MB_C_brd_V02_OCP.brd")
		(comment 1 "Grand Teton / footprints 6783-6785 of 8354")
	)
	(layers
		(0 "F.Cu" signal "TOP")
		(4 "In1.Cu" signal "GND")
		(6 "In2.Cu" signal "IN1")
		(8 "In3.Cu" signal "GND1")
		(10 "In4.Cu" signal "IN2")
		(12 "In5.Cu" signal "GND2")
		(14 "In6.Cu" signal "IN3")
		(16 "In7.Cu" signal "GND3")
		(18 "In8.Cu" signal "VCC")
		(20 "In9.Cu" signal "VCC1")
		(22 "In10.Cu" signal "GND4")
		(24 "In11.Cu" signal "IN4")
		(26 "In12.Cu" signal "GND5")
		(28 "In13.Cu" signal "IN5")
		(30 "In14.Cu" signal "GND6")
		(32 "In15.Cu" signal "IN6")
		(34 "In16.Cu" signal "GND7")
		(2 "B.Cu" signal "BOTTOM")
		(9 "F.Adhes" user "F.Adhesive")
		(11 "B.Adhes" user "B.Adhesive")
		(13 "F.Paste" user "Package Geometry/Pastemask Top")
		(15 "B.Paste" user "Package Geometry/Pastemask Bottom")
		(5 "F.SilkS" user "Ref Des/Silkscreen Top")
		(7 "B.SilkS" user "Ref Des/Silkscreen Bottom")
		(1 "F.Mask" user "Board Geometry/Soldermask Top")
		(3 "B.Mask" user "Board Geometry/Soldermask Bottom")
		(17 "Dwgs.User" user "User.Drawings")
		(19 "Cmts.User" user "User.Comments")
		(21 "Eco1.User" user "User.Eco1")
		(23 "Eco2.User" user "User.Eco2")
		(25 "Edge.Cuts" user "Board Geometry/Outline")
		(27 "Margin" user)
		(31 "F.CrtYd" user "Package Geometry/Place Bound Top")
		(29 "B.CrtYd" user "Package Geometry/Place Bound Bottom")
		(35 "F.Fab" user "Ref Des/Assembly Top")
		(33 "B.Fab" user "Ref Des/Assembly Bottom")
	)
	(footprint ""
		(layer "B.Cu")
		(at 368.51844 -395.43228)
		(property "Reference" "C1050"
			(at 0 0 0)
			(layer "B.SilkS")
			(hide yes)
			(effects
				(font
					(size 1.27 1.27)
				)
				(justify mirror)
			)
		)
		(property "Value" ""
			(at 0 0 0)
			(layer "B.Fab")
			(effects
				(font
					(size 1.27 1.27)
				)
				(justify mirror)
			)
		)
		(duplicate_pad_numbers_are_jumpers no)
		(fp_line
			(start -0.299974 -0.150114)
			(end -0.299974 0.150114)
			(stroke
				(width 0.1)
				(type default)
			)
			(layer "B.Fab")
		)
		(fp_line
			(start -0.299974 0.150114)
			(end 0.299974 0.150114)
			(stroke
				(width 0.1)
				(type default)
			)
			(layer "B.Fab")
		)
		(fp_line
			(start 0.299974 -0.150114)
			(end -0.299974 -0.150114)
			(stroke
				(width 0.1)
				(type default)
			)
			(layer "B.Fab")
		)
		(fp_line
			(start 0.299974 0.150114)
			(end 0.299974 -0.150114)
			(stroke
				(width 0.1)
				(type default)
			)
			(layer "B.Fab")
		)
		(pad "1" smd rect
			(at 0.2667 0 180)
			(size 0.3048 0.381)
			(layers "B.Cu" "B.Mask" "B.Paste")
			(net "P0V9_CPU0_RT3_2A")
		)
		(pad "2" smd rect
			(at -0.2667 0 180)
			(size 0.3048 0.381)
			(layers "B.Cu" "B.Mask" "B.Paste")
			(net "GND")
		)
	)
	(footprint ""
		(layer "B.Cu")
		(at 413.975804 -361.427014 -90)
		(property "Reference" "PR127"
			(at 0 0 90)
			(layer "B.SilkS")
			(hide yes)
			(effects
				(font
					(size 1.27 1.27)
				)
				(justify mirror)
			)
		)
		(property "Value" ""
			(at 0 0 90)
			(layer "B.Fab")
			(effects
				(font
					(size 1.27 1.27)
				)
				(justify mirror)
			)
		)
		(duplicate_pad_numbers_are_jumpers no)
		(fp_line
			(start -0.7874 0.4064)
			(end 0.7874 0.4064)
			(stroke
				(width 0.1524)
				(type default)
			)
			(layer "B.SilkS")
		)
		(fp_line
			(start 0.7874 0.4064)
			(end 0.7874 -0.4064)
			(stroke
				(width 0.1524)
				(type default)
			)
			(layer "B.SilkS")
		)
		(fp_line
			(start -0.7874 -0.4064)
			(end -0.7874 0.4064)
			(stroke
				(width 0.1524)
				(type default)
			)
			(layer "B.SilkS")
		)
		(fp_line
			(start 0.7874 -0.4064)
			(end -0.7874 -0.4064)
			(stroke
				(width 0.1524)
				(type default)
			)
			(layer "B.SilkS")
		)
		(fp_line
			(start -0.67945 0.3048)
			(end -0.120396 0.3048)
			(stroke
				(width 0.1)
				(type default)
			)
			(layer "B.Fab")
		)
		(fp_line
			(start -0.120396 0.3048)
			(end -0.120396 0.2794)
			(stroke
				(width 0.1)
				(type default)
			)
			(layer "B.Fab")
		)
		(fp_line
			(start 0.12065 0.3048)
			(end 0.67945 0.3048)
			(stroke
				(width 0.1)
				(type default)
			)
			(layer "B.Fab")
		)
		(fp_line
			(start 0.67945 0.3048)
			(end 0.67945 -0.305054)
			(stroke
				(width 0.1)
				(type default)
			)
			(layer "B.Fab")
		)
		(fp_line
			(start -0.120396 0.2794)
			(end 0.12065 0.2794)
			(stroke
				(width 0.1)
				(type default)
			)
			(layer "B.Fab")
		)
		(fp_line
			(start 0.12065 0.2794)
			(end 0.12065 0.3048)
			(stroke
				(width 0.1)
				(type default)
			)
			(layer "B.Fab")
		)
		(fp_line
			(start -0.12065 -0.2794)
			(end -0.12065 -0.3048)
			(stroke
				(width 0.1)
				(type default)
			)
			(layer "B.Fab")
		)
		(fp_line
			(start 0.12065 -0.2794)
			(end -0.12065 -0.2794)
			(stroke
				(width 0.1)
				(type default)
			)
			(layer "B.Fab")
		)
		(fp_line
			(start -0.67945 -0.3048)
			(end -0.67945 0.3048)
			(stroke
				(width 0.1)
				(type default)
			)
			(layer "B.Fab")
		)
		(fp_line
			(start -0.12065 -0.3048)
			(end -0.67945 -0.3048)
			(stroke
				(width 0.1)
				(type default)
			)
			(layer "B.Fab")
		)
		(fp_line
			(start 0.12065 -0.305054)
			(end 0.12065 -0.2794)
			(stroke
				(width 0.1)
				(type default)
			)
			(layer "B.Fab")
		)
		(fp_line
			(start 0.67945 -0.305054)
			(end 0.12065 -0.305054)
			(stroke
				(width 0.1)
				(type default)
			)
			(layer "B.Fab")
		)
		(pad "1" smd circle
			(at 0.40005 0 90)
			(size 0 0)
			(layers "B.Cu" "B.Mask" "B.Paste")
			(net "PVDD11_S3_P0_RESET_N_R")
		)
		(pad "2" smd circle
			(at -0.40005 0 90)
			(size 0 0)
			(layers "B.Cu" "B.Mask" "B.Paste")
			(net "GND")
		)
	)
	(footprint ""
		(layer "B.Cu")
		(at 14.840458 -418.817298)
		(property "Reference" "C6010"
			(at 0 0 0)
			(layer "B.SilkS")
			(hide yes)
			(effects
				(font
					(size 1.27 1.27)
				)
				(justify mirror)
			)
		)
		(property "Value" ""
			(at 0 0 0)
			(layer "B.Fab")
			(effects
				(font
					(size 1.27 1.27)
				)
				(justify mirror)
			)
		)
		(duplicate_pad_numbers_are_jumpers no)
		(fp_line
			(start -1.524 -0.762)
			(end -1.524 0.762)
			(stroke
				(width 0.1524)
				(type default)
			)
			(layer "B.SilkS")
		)
		(fp_line
			(start -1.524 0.762)
			(end 1.524 0.762)
			(stroke
				(width 0.1524)
				(type default)
			)
			(layer "B.SilkS")
		)
		(fp_line
			(start 1.524 -0.762)
			(end -1.524 -0.762)
			(stroke
				(width 0.1524)
				(type default)
			)
			(layer "B.SilkS")
		)
		(fp_line
			(start 1.524 0.762)
			(end 1.524 -0.762)
			(stroke
				(width 0.1524)
				(type default)
			)
			(layer "B.SilkS")
		)
		(fp_line
			(start -1.1049 -0.724916)
			(end 1.1049 -0.724916)
			(stroke
				(width 0.1)
				(type default)
			)
			(layer "B.Fab")
		)
		(fp_line
			(start -1.1049 0.724916)
			(end -1.1049 -0.724916)
			(stroke
				(width 0.1)
				(type default)
			)
			(layer "B.Fab")
		)
		(fp_line
			(start 1.1049 -0.724916)
			(end 1.1049 0.724916)
			(stroke
				(width 0.1)
				(type default)
			)
			(layer "B.Fab")
		)
		(fp_line
			(start 1.1049 0.724916)
			(end -1.1049 0.724916)
			(stroke
				(width 0.1)
				(type default)
			)
			(layer "B.Fab")
		)
		(pad "1" smd rect
			(at 0.889 0)
			(size 1.016 1.27)
			(layers "B.Cu" "B.Mask" "B.Paste")
			(net "P3V3_AUX")
		)
		(pad "2" smd rect
			(at -0.889 0)
			(size 1.016 1.27)
			(layers "B.Cu" "B.Mask" "B.Paste")
			(net "GND")
		)
	)
)
